(kicad_pcb
	(version 20260206)
	(generator "pcbnew")
	(generator_version "10.0")
	(general
		(thickness 1.6)
		(legacy_teardrops no)
	)
	(paper "A4")
	(title_block
		(title "01162023_DA0F0TEBIF0_F0T_Expander_BD_F_brd_V02_OCP.brd")
		(comment 1 "Grand Teton / footprints 7449-7456 of 9728")
	)
	(layers
		(0 "F.Cu" signal "TOP")
		(4 "In1.Cu" signal "GND")
		(6 "In2.Cu" signal "VCC")
		(8 "In3.Cu" signal "VCC1")
		(10 "In4.Cu" signal "GND1")
		(12 "In5.Cu" signal "IN1")
		(14 "In6.Cu" signal "GND2")
		(16 "In7.Cu" signal "IN2")
		(18 "In8.Cu" signal "GND3")
		(20 "In9.Cu" signal "IN3")
		(22 "In10.Cu" signal "GND4")
		(24 "In11.Cu" signal "IN4")
		(26 "In12.Cu" signal "GND5")
		(28 "In13.Cu" signal "IN5")
		(30 "In14.Cu" signal "GND6")
		(32 "In15.Cu" signal "IN6")
		(34 "In16.Cu" signal "GND7")
		(2 "B.Cu" signal "BOTTOM")
		(9 "F.Adhes" user "F.Adhesive")
		(11 "B.Adhes" user "B.Adhesive")
		(13 "F.Paste" user "Package Geometry/Pastemask Top")
		(15 "B.Paste" user "Package Geometry/Pastemask Bottom")
		(5 "F.SilkS" user "Ref Des/Silkscreen Top")
		(7 "B.SilkS" user "Ref Des/Silkscreen Bottom")
		(1 "F.Mask" user "Board Geometry/Soldermask Top")
		(3 "B.Mask" user "Board Geometry/Soldermask Bottom")
		(17 "Dwgs.User" user "User.Drawings")
		(19 "Cmts.User" user "User.Comments")
		(21 "Eco1.User" user "User.Eco1")
		(23 "Eco2.User" user "User.Eco2")
		(25 "Edge.Cuts" user "Board Geometry/Outline")
		(27 "Margin" user)
		(31 "F.CrtYd" user "Package Geometry/Place Bound Top")
		(29 "B.CrtYd" user "Package Geometry/Place Bound Bottom")
		(35 "F.Fab" user "Ref Des/Assembly Top")
		(33 "B.Fab" user "Ref Des/Assembly Bottom")
	)
	(footprint ""
		(layer "B.Cu")
		(at 397.85544 -155.0416)
		(property "Reference" "R333"
			(at 0 0 0)
			(layer "B.SilkS")
			(hide yes)
			(effects
				(font
					(size 1.27 1.27)
				)
				(justify mirror)
			)
		)
		(property "Value" ""
			(at 0 0 0)
			(layer "B.Fab")
			(effects
				(font
					(size 1.27 1.27)
				)
				(justify mirror)
			)
		)
		(duplicate_pad_numbers_are_jumpers no)
		(fp_line
			(start -0.7874 -0.4064)
			(end -0.7874 0.4064)
			(stroke
				(width 0.1524)
				(type default)
			)
			(layer "B.SilkS")
		)
		(fp_line
			(start -0.7874 0.4064)
			(end 0.7874 0.4064)
			(stroke
				(width 0.1524)
				(type default)
			)
			(layer "B.SilkS")
		)
		(fp_line
			(start 0.7874 -0.4064)
			(end -0.7874 -0.4064)
			(stroke
				(width 0.1524)
				(type default)
			)
			(layer "B.SilkS")
		)
		(fp_line
			(start 0.7874 0.4064)
			(end 0.7874 -0.4064)
			(stroke
				(width 0.1524)
				(type default)
			)
			(layer "B.SilkS")
		)
		(fp_line
			(start -0.67945 -0.3048)
			(end -0.67945 0.3048)
			(stroke
				(width 0.1)
				(type default)
			)
			(layer "B.Fab")
		)
		(fp_line
			(start -0.67945 0.3048)
			(end -0.120396 0.3048)
			(stroke
				(width 0.1)
				(type default)
			)
			(layer "B.Fab")
		)
		(fp_line
			(start -0.12065 -0.3048)
			(end -0.67945 -0.3048)
			(stroke
				(width 0.1)
				(type default)
			)
			(layer "B.Fab")
		)
		(fp_line
			(start -0.12065 -0.2794)
			(end -0.12065 -0.3048)
			(stroke
				(width 0.1)
				(type default)
			)
			(layer "B.Fab")
		)
		(fp_line
			(start -0.120396 0.2794)
			(end 0.12065 0.2794)
			(stroke
				(width 0.1)
				(type default)
			)
			(layer "B.Fab")
		)
		(fp_line
			(start -0.120396 0.3048)
			(end -0.120396 0.2794)
			(stroke
				(width 0.1)
				(type default)
			)
			(layer "B.Fab")
		)
		(fp_line
			(start 0.12065 -0.305054)
			(end 0.12065 -0.2794)
			(stroke
				(width 0.1)
				(type default)
			)
			(layer "B.Fab")
		)
		(fp_line
			(start 0.12065 -0.2794)
			(end -0.12065 -0.2794)
			(stroke
				(width 0.1)
				(type default)
			)
			(layer "B.Fab")
		)
		(fp_line
			(start 0.12065 0.2794)
			(end 0.12065 0.3048)
			(stroke
				(width 0.1)
				(type default)
			)
			(layer "B.Fab")
		)
		(fp_line
			(start 0.12065 0.3048)
			(end 0.67945 0.3048)
			(stroke
				(width 0.1)
				(type default)
			)
			(layer "B.Fab")
		)
		(fp_line
			(start 0.67945 -0.305054)
			(end 0.12065 -0.305054)
			(stroke
				(width 0.1)
				(type default)
			)
			(layer "B.Fab")
		)
		(fp_line
			(start 0.67945 0.3048)
			(end 0.67945 -0.305054)
			(stroke
				(width 0.1)
				(type default)
			)
			(layer "B.Fab")
		)
		(pad "1" smd circle
			(at 0.40005 0 180)
			(size 0 0)
			(layers "B.Cu" "B.Mask" "B.Paste")
			(net "NIC6_SLOT_ID1")
		)
		(pad "2" smd circle
			(at -0.40005 0 180)
			(size 0 0)
			(layers "B.Cu" "B.Mask" "B.Paste")
			(net "P3V3_NIC6")
		)
	)
	(footprint ""
		(layer "B.Cu")
		(at 375.58853 -236.556296 180)
		(property "Reference" "R910"
			(at 0 0 0)
			(layer "B.SilkS")
			(hide yes)
			(effects
				(font
					(size 1.27 1.27)
				)
				(justify mirror)
			)
		)
		(property "Value" ""
			(at 0 0 0)
			(layer "B.Fab")
			(effects
				(font
					(size 1.27 1.27)
				)
				(justify mirror)
			)
		)
		(duplicate_pad_numbers_are_jumpers no)
		(fp_line
			(start 0.7874 0.4064)
			(end 0.7874 -0.4064)
			(stroke
				(width 0.1524)
				(type default)
			)
			(layer "B.SilkS")
		)
		(fp_line
			(start 0.7874 -0.4064)
			(end -0.7874 -0.4064)
			(stroke
				(width 0.1524)
				(type default)
			)
			(layer "B.SilkS")
		)
		(fp_line
			(start -0.7874 0.4064)
			(end 0.7874 0.4064)
			(stroke
				(width 0.1524)
				(type default)
			)
			(layer "B.SilkS")
		)
		(fp_line
			(start -0.7874 -0.4064)
			(end -0.7874 0.4064)
			(stroke
				(width 0.1524)
				(type default)
			)
			(layer "B.SilkS")
		)
		(fp_line
			(start 0.67945 0.3048)
			(end 0.67945 -0.305054)
			(stroke
				(width 0.1)
				(type default)
			)
			(layer "B.Fab")
		)
		(fp_line
			(start 0.67945 -0.305054)
			(end 0.12065 -0.305054)
			(stroke
				(width 0.1)
				(type default)
			)
			(layer "B.Fab")
		)
		(fp_line
			(start 0.12065 0.3048)
			(end 0.67945 0.3048)
			(stroke
				(width 0.1)
				(type default)
			)
			(layer "B.Fab")
		)
		(fp_line
			(start 0.12065 0.2794)
			(end 0.12065 0.3048)
			(stroke
				(width 0.1)
				(type default)
			)
			(layer "B.Fab")
		)
		(fp_line
			(start 0.12065 -0.2794)
			(end -0.12065 -0.2794)
			(stroke
				(width 0.1)
				(type default)
			)
			(layer "B.Fab")
		)
		(fp_line
			(start 0.12065 -0.305054)
			(end 0.12065 -0.2794)
			(stroke
				(width 0.1)
				(type default)
			)
			(layer "B.Fab")
		)
		(fp_line
			(start -0.120396 0.3048)
			(end -0.120396 0.2794)
			(stroke
				(width 0.1)
				(type default)
			)
			(layer "B.Fab")
		)
		(fp_line
			(start -0.120396 0.2794)
			(end 0.12065 0.2794)
			(stroke
				(width 0.1)
				(type default)
			)
			(layer "B.Fab")
		)
		(fp_line
			(start -0.12065 -0.2794)
			(end -0.12065 -0.3048)
			(stroke
				(width 0.1)
				(type default)
			)
			(layer "B.Fab")
		)
		(fp_line
			(start -0.12065 -0.3048)
			(end -0.67945 -0.3048)
			(stroke
				(width 0.1)
				(type default)
			)
			(layer "B.Fab")
		)
		(fp_line
			(start -0.67945 0.3048)
			(end -0.120396 0.3048)
			(stroke
				(width 0.1)
				(type default)
			)
			(layer "B.Fab")
		)
		(fp_line
			(start -0.67945 -0.3048)
			(end -0.67945 0.3048)
			(stroke
				(width 0.1)
				(type default)
			)
			(layer "B.Fab")
		)
		(pad "1" smd circle
			(at 0.40005 0)
			(size 0 0)
			(layers "B.Cu" "B.Mask" "B.Paste")
			(net "FT4232_SDB_EEPROM_R_CS")
		)
		(pad "2" smd circle
			(at -0.40005 0)
			(size 0 0)
			(layers "B.Cu" "B.Mask" "B.Paste")
			(net "P3V3_AUX")
		)
	)
	(footprint ""
		(layer "B.Cu")
		(at 365.864394 -321.84594 -90)
		(property "Reference" "R6539"
			(at 0 0 90)
			(layer "B.SilkS")
			(hide yes)
			(effects
				(font
					(size 1.27 1.27)
				)
				(justify mirror)
			)
		)
		(property "Value" ""
			(at 0 0 90)
			(layer "B.Fab")
			(effects
				(font
					(size 1.27 1.27)
				)
				(justify mirror)
			)
		)
		(duplicate_pad_numbers_are_jumpers no)
		(fp_line
			(start -0.7874 0.4064)
			(end 0.7874 0.4064)
			(stroke
				(width 0.1524)
				(type default)
			)
			(layer "B.SilkS")
		)
		(fp_line
			(start 0.7874 0.4064)
			(end 0.7874 -0.4064)
			(stroke
				(width 0.1524)
				(type default)
			)
			(layer "B.SilkS")
		)
		(fp_line
			(start -0.7874 -0.4064)
			(end -0.7874 0.4064)
			(stroke
				(width 0.1524)
				(type default)
			)
			(layer "B.SilkS")
		)
		(fp_line
			(start 0.7874 -0.4064)
			(end -0.7874 -0.4064)
			(stroke
				(width 0.1524)
				(type default)
			)
			(layer "B.SilkS")
		)
		(fp_line
			(start -0.67945 0.3048)
			(end -0.120396 0.3048)
			(stroke
				(width 0.1)
				(type default)
			)
			(layer "B.Fab")
		)
		(fp_line
			(start -0.120396 0.3048)
			(end -0.120396 0.2794)
			(stroke
				(width 0.1)
				(type default)
			)
			(layer "B.Fab")
		)
		(fp_line
			(start 0.12065 0.3048)
			(end 0.67945 0.3048)
			(stroke
				(width 0.1)
				(type default)
			)
			(layer "B.Fab")
		)
		(fp_line
			(start 0.67945 0.3048)
			(end 0.67945 -0.305054)
			(stroke
				(width 0.1)
				(type default)
			)
			(layer "B.Fab")
		)
		(fp_line
			(start -0.120396 0.2794)
			(end 0.12065 0.2794)
			(stroke
				(width 0.1)
				(type default)
			)
			(layer "B.Fab")
		)
		(fp_line
			(start 0.12065 0.2794)
			(end 0.12065 0.3048)
			(stroke
				(width 0.1)
				(type default)
			)
			(layer "B.Fab")
		)
		(fp_line
			(start -0.12065 -0.2794)
			(end -0.12065 -0.3048)
			(stroke
				(width 0.1)
				(type default)
			)
			(layer "B.Fab")
		)
		(fp_line
			(start 0.12065 -0.2794)
			(end -0.12065 -0.2794)
			(stroke
				(width 0.1)
				(type default)
			)
			(layer "B.Fab")
		)
		(fp_line
			(start -0.67945 -0.3048)
			(end -0.67945 0.3048)
			(stroke
				(width 0.1)
				(type default)
			)
			(layer "B.Fab")
		)
		(fp_line
			(start -0.12065 -0.3048)
			(end -0.67945 -0.3048)
			(stroke
				(width 0.1)
				(type default)
			)
			(layer "B.Fab")
		)
		(fp_line
			(start 0.12065 -0.305054)
			(end 0.12065 -0.2794)
			(stroke
				(width 0.1)
				(type default)
			)
			(layer "B.Fab")
		)
		(fp_line
			(start 0.67945 -0.305054)
			(end 0.12065 -0.305054)
			(stroke
				(width 0.1)
				(type default)
			)
			(layer "B.Fab")
		)
		(pad "1" smd circle
			(at 0.40005 0 90)
			(size 0 0)
			(layers "B.Cu" "B.Mask" "B.Paste")
			(net "P0V8_SERDES_VDDA_PEX3")
		)
		(pad "2" smd circle
			(at -0.40005 0 90)
			(size 0 0)
			(layers "B.Cu" "B.Mask" "B.Paste")
			(net "P0V8_SERDES_VDDA_PEX3_C4")
		)
	)
	(footprint ""
		(layer "B.Cu")
		(at 303.954942 -98.552)
		(property "Reference" "R257"
			(at 0 0 0)
			(layer "B.SilkS")
			(hide yes)
			(effects
				(font
					(size 1.27 1.27)
				)
				(justify mirror)
			)
		)
		(property "Value" ""
			(at 0 0 0)
			(layer "B.Fab")
			(effects
				(font
					(size 1.27 1.27)
				)
				(justify mirror)
			)
		)
		(duplicate_pad_numbers_are_jumpers no)
		(fp_line
			(start -0.7874 -0.4064)
			(end -0.7874 0.4064)
			(stroke
				(width 0.1524)
				(type default)
			)
			(layer "B.SilkS")
		)
		(fp_line
			(start -0.7874 0.4064)
			(end 0.7874 0.4064)
			(stroke
				(width 0.1524)
				(type default)
			)
			(layer "B.SilkS")
		)
		(fp_line
			(start 0.7874 -0.4064)
			(end -0.7874 -0.4064)
			(stroke
				(width 0.1524)
				(type default)
			)
			(layer "B.SilkS")
		)
		(fp_line
			(start 0.7874 0.4064)
			(end 0.7874 -0.4064)
			(stroke
				(width 0.1524)
				(type default)
			)
			(layer "B.SilkS")
		)
		(fp_line
			(start -0.67945 -0.3048)
			(end -0.67945 0.3048)
			(stroke
				(width 0.1)
				(type default)
			)
			(layer "B.Fab")
		)
		(fp_line
			(start -0.67945 0.3048)
			(end -0.120396 0.3048)
			(stroke
				(width 0.1)
				(type default)
			)
			(layer "B.Fab")
		)
		(fp_line
			(start -0.12065 -0.3048)
			(end -0.67945 -0.3048)
			(stroke
				(width 0.1)
				(type default)
			)
			(layer "B.Fab")
		)
		(fp_line
			(start -0.12065 -0.2794)
			(end -0.12065 -0.3048)
			(stroke
				(width 0.1)
				(type default)
			)
			(layer "B.Fab")
		)
		(fp_line
			(start -0.120396 0.2794)
			(end 0.12065 0.2794)
			(stroke
				(width 0.1)
				(type default)
			)
			(layer "B.Fab")
		)
		(fp_line
			(start -0.120396 0.3048)
			(end -0.120396 0.2794)
			(stroke
				(width 0.1)
				(type default)
			)
			(layer "B.Fab")
		)
		(fp_line
			(start 0.12065 -0.305054)
			(end 0.12065 -0.2794)
			(stroke
				(width 0.1)
				(type default)
			)
			(layer "B.Fab")
		)
		(fp_line
			(start 0.12065 -0.2794)
			(end -0.12065 -0.2794)
			(stroke
				(width 0.1)
				(type default)
			)
			(layer "B.Fab")
		)
		(fp_line
			(start 0.12065 0.2794)
			(end 0.12065 0.3048)
			(stroke
				(width 0.1)
				(type default)
			)
			(layer "B.Fab")
		)
		(fp_line
			(start 0.12065 0.3048)
			(end 0.67945 0.3048)
			(stroke
				(width 0.1)
				(type default)
			)
			(layer "B.Fab")
		)
		(fp_line
			(start 0.67945 -0.305054)
			(end 0.12065 -0.305054)
			(stroke
				(width 0.1)
				(type default)
			)
			(layer "B.Fab")
		)
		(fp_line
			(start 0.67945 0.3048)
			(end 0.67945 -0.305054)
			(stroke
				(width 0.1)
				(type default)
			)
			(layer "B.Fab")
		)
		(pad "1" smd circle
			(at 0.40005 0 180)
			(size 0 0)
			(layers "B.Cu" "B.Mask" "B.Paste")
			(net "NIC5_MAIN_PWR_EN_R")
		)
		(pad "2" smd circle
			(at -0.40005 0 180)
			(size 0 0)
			(layers "B.Cu" "B.Mask" "B.Paste")
			(net "NIC5_MAIN_PWR_EN")
		)
	)
	(footprint ""
		(layer "B.Cu")
		(at 409.897326 -108.465366)
		(property "Reference" "R386"
			(at 0 0 0)
			(layer "B.SilkS")
			(hide yes)
			(effects
				(font
					(size 1.27 1.27)
				)
				(justify mirror)
			)
		)
		(property "Value" ""
			(at 0 0 0)
			(layer "B.Fab")
			(effects
				(font
					(size 1.27 1.27)
				)
				(justify mirror)
			)
		)
		(duplicate_pad_numbers_are_jumpers no)
		(fp_line
			(start -0.7874 -0.4064)
			(end -0.7874 0.4064)
			(stroke
				(width 0.1524)
				(type default)
			)
			(layer "B.SilkS")
		)
		(fp_line
			(start -0.7874 0.4064)
			(end 0.7874 0.4064)
			(stroke
				(width 0.1524)
				(type default)
			)
			(layer "B.SilkS")
		)
		(fp_line
			(start 0.7874 -0.4064)
			(end -0.7874 -0.4064)
			(stroke
				(width 0.1524)
				(type default)
			)
			(layer "B.SilkS")
		)
		(fp_line
			(start 0.7874 0.4064)
			(end 0.7874 -0.4064)
			(stroke
				(width 0.1524)
				(type default)
			)
			(layer "B.SilkS")
		)
		(fp_line
			(start -0.67945 -0.3048)
			(end -0.67945 0.3048)
			(stroke
				(width 0.1)
				(type default)
			)
			(layer "B.Fab")
		)
		(fp_line
			(start -0.67945 0.3048)
			(end -0.120396 0.3048)
			(stroke
				(width 0.1)
				(type default)
			)
			(layer "B.Fab")
		)
		(fp_line
			(start -0.12065 -0.3048)
			(end -0.67945 -0.3048)
			(stroke
				(width 0.1)
				(type default)
			)
			(layer "B.Fab")
		)
		(fp_line
			(start -0.12065 -0.2794)
			(end -0.12065 -0.3048)
			(stroke
				(width 0.1)
				(type default)
			)
			(layer "B.Fab")
		)
		(fp_line
			(start -0.120396 0.2794)
			(end 0.12065 0.2794)
			(stroke
				(width 0.1)
				(type default)
			)
			(layer "B.Fab")
		)
		(fp_line
			(start -0.120396 0.3048)
			(end -0.120396 0.2794)
			(stroke
				(width 0.1)
				(type default)
			)
			(layer "B.Fab")
		)
		(fp_line
			(start 0.12065 -0.305054)
			(end 0.12065 -0.2794)
			(stroke
				(width 0.1)
				(type default)
			)
			(layer "B.Fab")
		)
		(fp_line
			(start 0.12065 -0.2794)
			(end -0.12065 -0.2794)
			(stroke
				(width 0.1)
				(type default)
			)
			(layer "B.Fab")
		)
		(fp_line
			(start 0.12065 0.2794)
			(end 0.12065 0.3048)
			(stroke
				(width 0.1)
				(type default)
			)
			(layer "B.Fab")
		)
		(fp_line
			(start 0.12065 0.3048)
			(end 0.67945 0.3048)
			(stroke
				(width 0.1)
				(type default)
			)
			(layer "B.Fab")
		)
		(fp_line
			(start 0.67945 -0.305054)
			(end 0.12065 -0.305054)
			(stroke
				(width 0.1)
				(type default)
			)
			(layer "B.Fab")
		)
		(fp_line
			(start 0.67945 0.3048)
			(end 0.67945 -0.305054)
			(stroke
				(width 0.1)
				(type default)
			)
			(layer "B.Fab")
		)
		(pad "1" smd circle
			(at 0.40005 0 180)
			(size 0 0)
			(layers "B.Cu" "B.Mask" "B.Paste")
			(net "NIC7_BIF0_N")
		)
		(pad "2" smd circle
			(at -0.40005 0 180)
			(size 0 0)
			(layers "B.Cu" "B.Mask" "B.Paste")
			(net "P3V3_AUX")
		)
	)
	(footprint ""
		(layer "B.Cu")
		(at 168.150032 -303.499774 -90)
		(property "Reference" "C3077"
			(at 0 0 90)
			(layer "B.SilkS")
			(hide yes)
			(effects
				(font
					(size 1.27 1.27)
				)
				(justify mirror)
			)
		)
		(property "Value" ""
			(at 0 0 90)
			(layer "B.Fab")
			(effects
				(font
					(size 1.27 1.27)
				)
				(justify mirror)
			)
		)
		(duplicate_pad_numbers_are_jumpers no)
		(fp_line
			(start -0.299974 0.150114)
			(end 0.299974 0.150114)
			(stroke
				(width 0.1)
				(type default)
			)
			(layer "B.Fab")
		)
		(fp_line
			(start 0.299974 0.150114)
			(end 0.299974 -0.150114)
			(stroke
				(width 0.1)
				(type default)
			)
			(layer "B.Fab")
		)
		(fp_line
			(start -0.299974 -0.150114)
			(end -0.299974 0.150114)
			(stroke
				(width 0.1)
				(type default)
			)
			(layer "B.Fab")
		)
		(fp_line
			(start 0.299974 -0.150114)
			(end -0.299974 -0.150114)
			(stroke
				(width 0.1)
				(type default)
			)
			(layer "B.Fab")
		)
		(pad "1" smd rect
			(at 0.2667 0 90)
			(size 0.3048 0.381)
			(layers "B.Cu" "B.Mask" "B.Paste")
			(net "P1V25_PEX1")
		)
		(pad "2" smd rect
			(at -0.2667 0 90)
			(size 0.3048 0.381)
			(layers "B.Cu" "B.Mask" "B.Paste")
			(net "GND")
		)
	)
	(footprint ""
		(layer "B.Cu")
		(at 63.951358 -305.399948 -90)
		(property "Reference" "C2952"
			(at 0 0 90)
			(layer "B.SilkS")
			(hide yes)
			(effects
				(font
					(size 1.27 1.27)
				)
				(justify mirror)
			)
		)
		(property "Value" ""
			(at 0 0 90)
			(layer "B.Fab")
			(effects
				(font
					(size 1.27 1.27)
				)
				(justify mirror)
			)
		)
		(duplicate_pad_numbers_are_jumpers no)
		(fp_line
			(start -0.299974 0.150114)
			(end 0.299974 0.150114)
			(stroke
				(width 0.1)
				(type default)
			)
			(layer "B.Fab")
		)
		(fp_line
			(start 0.299974 0.150114)
			(end 0.299974 -0.150114)
			(stroke
				(width 0.1)
				(type default)
			)
			(layer "B.Fab")
		)
		(fp_line
			(start -0.299974 -0.150114)
			(end -0.299974 0.150114)
			(stroke
				(width 0.1)
				(type default)
			)
			(layer "B.Fab")
		)
		(fp_line
			(start 0.299974 -0.150114)
			(end -0.299974 -0.150114)
			(stroke
				(width 0.1)
				(type default)
			)
			(layer "B.Fab")
		)
		(pad "1" smd rect
			(at 0.2667 0 90)
			(size 0.3048 0.381)
			(layers "B.Cu" "B.Mask" "B.Paste")
			(net "P1V25_SERDES_VDDPLL_PEX0")
		)
		(pad "2" smd rect
			(at -0.2667 0 90)
			(size 0.3048 0.381)
			(layers "B.Cu" "B.Mask" "B.Paste")
			(net "GND")
		)
	)
	(footprint ""
		(layer "B.Cu")
		(at 285.199836 -288.299906 90)
		(property "Reference" "C3282"
			(at 0 0 90)
			(layer "B.SilkS")
			(hide yes)
			(effects
				(font
					(size 1.27 1.27)
				)
				(justify mirror)
			)
		)
		(property "Value" ""
			(at 0 0 90)
			(layer "B.Fab")
			(effects
				(font
					(size 1.27 1.27)
				)
				(justify mirror)
			)
		)
		(duplicate_pad_numbers_are_jumpers no)
		(fp_line
			(start 0.299974 -0.150114)
			(end -0.299974 -0.150114)
			(stroke
				(width 0.1)
				(type default)
			)
			(layer "B.Fab")
		)
		(fp_line
			(start -0.299974 -0.150114)
			(end -0.299974 0.150114)
			(stroke
				(width 0.1)
				(type default)
			)
			(layer "B.Fab")
		)
		(fp_line
			(start 0.299974 0.150114)
			(end 0.299974 -0.150114)
			(stroke
				(width 0.1)
				(type default)
			)
			(layer "B.Fab")
		)
		(fp_line
			(start -0.299974 0.150114)
			(end 0.299974 0.150114)
			(stroke
				(width 0.1)
				(type default)
			)
			(layer "B.Fab")
		)
		(pad "1" smd rect
			(at 0.2667 0 270)
			(size 0.3048 0.381)
			(layers "B.Cu" "B.Mask" "B.Paste")
			(net "P1V25_PEX2")
		)
		(pad "2" smd rect
			(at -0.2667 0 270)
			(size 0.3048 0.381)
			(layers "B.Cu" "B.Mask" "B.Paste")
			(net "GND")
		)
	)
)
